(kicad_pcb
	(version 20241229)
	(generator "pcbnew")
	(generator_version "9.0")
	(general
		(thickness 1.59)
		(legacy_teardrops no)
	)
	(paper "A3")
	(title_block
		(title "usb-c-power-adapter")
		(date "2025-06-24")
		(rev "1.1.2")
		(company "Antmicro")
		(comment 9 "footprints 79-83 of 122")
	)
	(layers
		(0 "F.Cu" signal)
		(4 "In1.Cu" signal)
		(6 "In2.Cu" signal)
		(2 "B.Cu" signal)
		(9 "F.Adhes" user "F.Adhesive")
		(11 "B.Adhes" user "B.Adhesive")
		(13 "F.Paste" user)
		(15 "B.Paste" user)
		(5 "F.SilkS" user "F.Silkscreen")
		(7 "B.SilkS" user "B.Silkscreen")
		(1 "F.Mask" user)
		(3 "B.Mask" user)
		(17 "Dwgs.User" user "User.Drawings")
		(19 "Cmts.User" user "User.Comments")
		(21 "Eco1.User" user "User.Eco1")
		(23 "Eco2.User" user "User.Eco2")
		(25 "Edge.Cuts" user)
		(27 "Margin" user)
		(31 "F.CrtYd" user "F.Courtyard")
		(29 "B.CrtYd" user "B.Courtyard")
		(35 "F.Fab" user)
		(33 "B.Fab" user)
	)
	(footprint "antmicro-footprints:C_0402_1005Metric"
		(layer "B.Cu")
		(at 86.45 80.5 -90)
		(descr "Capacitor SMD 0402")
		(tags "capacitor SMD 0402")
		(property "Reference" "C24"
			(at -3.157 -0.429 90)
			(layer "B.SilkS")
			(effects
				(font
					(size 0.7 0.7)
					(thickness 0.15)
				)
				(justify left bottom mirror)
			)
		)
		(property "Value" "C_100n_50V_X8L_0402"
			(at -1.022927 -2.155213 90)
			(layer "B.Fab")
			(effects
				(font
					(size 0.7 0.7)
					(thickness 0.15)
				)
				(justify left bottom mirror)
			)
		)
		(property "Datasheet" "https://www.murata.com/products/productdetail?partno=GCM155L8EH104KE07%23"
			(at 0 0 270)
			(layer "F.Fab")
			(hide yes)
			(effects
				(font
					(size 1.27 1.27)
					(thickness 0.15)
				)
			)
		)
		(property "Description" "SMD Multilayer Ceramic Capacitor, 100nF, 50V, 0402, ±10%, X8L"
			(at 0 0 270)
			(layer "F.Fab")
			(hide yes)
			(effects
				(font
					(size 1.27 1.27)
					(thickness 0.15)
				)
			)
		)
		(property "MPN" "GCM155L8EH104KE07D"
			(at 0 0 270)
			(unlocked yes)
			(layer "B.Fab")
			(hide yes)
			(effects
				(font
					(size 1 1)
					(thickness 0.15)
				)
				(justify mirror)
			)
		)
		(property "Val" "100n"
			(at 0 0 270)
			(unlocked yes)
			(layer "B.Fab")
			(hide yes)
			(effects
				(font
					(size 1 1)
					(thickness 0.15)
				)
				(justify mirror)
			)
		)
		(property "Voltage" "50V"
			(at 0 0 270)
			(unlocked yes)
			(layer "B.Fab")
			(hide yes)
			(effects
				(font
					(size 1 1)
					(thickness 0.15)
				)
				(justify mirror)
			)
		)
		(property "Dielectric" "X8L"
			(at 0 0 270)
			(unlocked yes)
			(layer "B.Fab")
			(hide yes)
			(effects
				(font
					(size 1 1)
					(thickness 0.15)
				)
				(justify mirror)
			)
		)
		(property "Manufacturer" "Murata"
			(at 0 0 270)
			(unlocked yes)
			(layer "B.Fab")
			(hide yes)
			(effects
				(font
					(size 1 1)
					(thickness 0.15)
				)
				(justify mirror)
			)
		)
		(property "License" "Apache-2.0"
			(at 0 0 270)
			(unlocked yes)
			(layer "B.Fab")
			(hide yes)
			(effects
				(font
					(size 1 1)
					(thickness 0.15)
				)
				(justify mirror)
			)
		)
		(property "Author" "Antmicro"
			(at 0 0 270)
			(unlocked yes)
			(layer "B.Fab")
			(hide yes)
			(effects
				(font
					(size 1 1)
					(thickness 0.15)
				)
				(justify mirror)
			)
		)
		(sheetname "/DC-DC Converters/")
		(sheetfile "dc-dc_converters.kicad_sch")
		(attr smd)
		(fp_rect
			(start -0.925 0.47)
			(end 0.925 -0.47)
			(stroke
				(width 0.05)
				(type default)
			)
			(fill no)
			(layer "B.CrtYd")
		)
		(fp_line
			(start -0.494 0.25)
			(end -0.494 -0.248)
			(stroke
				(width 0.15)
				(type solid)
			)
			(layer "B.Fab")
		)
		(fp_line
			(start 0.504 0.25)
			(end -0.494 0.25)
			(stroke
				(width 0.15)
				(type solid)
			)
			(layer "B.Fab")
		)
		(fp_line
			(start -0.494 -0.248)
			(end 0.504 -0.248)
			(stroke
				(width 0.15)
				(type solid)
			)
			(layer "B.Fab")
		)
		(fp_line
			(start 0.504 -0.248)
			(end 0.504 0.25)
			(stroke
				(width 0.15)
				(type solid)
			)
			(layer "B.Fab")
		)
		(pad "1" smd roundrect
			(at -0.48 0 270)
			(size 0.59 0.64)
			(layers "B.Cu" "B.Mask" "B.Paste")
			(roundrect_rratio 0.25)
			(net 23 "Net-(U4-SW)")
			(pintype "passive")
		)
		(pad "2" smd roundrect
			(at 0.48 0 270)
			(size 0.59 0.64)
			(layers "B.Cu" "B.Mask" "B.Paste")
			(roundrect_rratio 0.25)
			(net 24 "Net-(U4-BST)")
			(pintype "passive")
		)
	)
	(footprint "antmicro-footprints:R_0402_1005Metric"
		(layer "B.Cu")
		(at 87.626 89.1 90)
		(descr "Resistor SMD 0402")
		(tags "resistor SMD 0402")
		(property "Reference" "R2"
			(at 0.85 2.75 90)
			(layer "B.SilkS")
			(effects
				(font
					(size 0.7 0.7)
					(thickness 0.15)
				)
				(justify left bottom mirror)
			)
		)
		(property "Value" "R_5k23_0402"
			(at -1.011843 -1.772047 90)
			(layer "B.Fab")
			(effects
				(font
					(size 0.7 0.7)
					(thickness 0.15)
				)
				(justify right bottom mirror)
			)
		)
		(property "Datasheet" "https://www.farnell.com/datasheets/3795017.pdf"
			(at 0 0 90)
			(layer "F.Fab")
			(hide yes)
			(effects
				(font
					(size 1.27 1.27)
					(thickness 0.15)
				)
			)
		)
		(property "Description" "SMD Chip Resistor, 5.23 kohm, ± 1%, 63 mW, 0402 [1005 Metric], Thick Film, General Purpose"
			(at 0 0 90)
			(layer "F.Fab")
			(hide yes)
			(effects
				(font
					(size 1.27 1.27)
					(thickness 0.15)
				)
			)
		)
		(property "MPN" "RC0402FR-075K23L"
			(at 0 0 90)
			(unlocked yes)
			(layer "B.Fab")
			(hide yes)
			(effects
				(font
					(size 1 1)
					(thickness 0.15)
				)
				(justify mirror)
			)
		)
		(property "Manufacturer" "YAGEO"
			(at 0 0 90)
			(unlocked yes)
			(layer "B.Fab")
			(hide yes)
			(effects
				(font
					(size 1 1)
					(thickness 0.15)
				)
				(justify mirror)
			)
		)
		(property "License" "Apache-2.0"
			(at 0 0 90)
			(unlocked yes)
			(layer "B.Fab")
			(hide yes)
			(effects
				(font
					(size 1 1)
					(thickness 0.15)
				)
				(justify mirror)
			)
		)
		(property "Author" "Antmicro"
			(at 0 0 90)
			(unlocked yes)
			(layer "B.Fab")
			(hide yes)
			(effects
				(font
					(size 1 1)
					(thickness 0.15)
				)
				(justify mirror)
			)
		)
		(property "Val" "5k23"
			(at 0 0 90)
			(unlocked yes)
			(layer "B.Fab")
			(hide yes)
			(effects
				(font
					(size 1 1)
					(thickness 0.15)
				)
				(justify mirror)
			)
		)
		(property "Tolerance" "1%"
			(at 0 0 90)
			(unlocked yes)
			(layer "B.Fab")
			(hide yes)
			(effects
				(font
					(size 1 1)
					(thickness 0.15)
				)
				(justify mirror)
			)
		)
		(sheetname "/DC-DC Converters/")
		(sheetfile "dc-dc_converters.kicad_sch")
		(attr smd)
		(fp_rect
			(start -0.925 0.47)
			(end 0.925 -0.47)
			(stroke
				(width 0.05)
				(type default)
			)
			(fill no)
			(layer "B.CrtYd")
		)
		(fp_rect
			(start -0.5 0.25)
			(end 0.5 -0.25)
			(stroke
				(width 0.15)
				(type solid)
			)
			(fill no)
			(layer "B.Fab")
		)
		(pad "1" smd roundrect
			(at -0.48 0 90)
			(size 0.59 0.64)
			(layers "B.Cu" "B.Mask" "B.Paste")
			(roundrect_rratio 0.25)
			(net 25 "+5V")
			(pintype "passive")
		)
		(pad "2" smd roundrect
			(at 0.48 0 90)
			(size 0.59 0.64)
			(layers "B.Cu" "B.Mask" "B.Paste")
			(roundrect_rratio 0.25)
			(net 40 "Net-(U3-FB)")
			(pintype "passive")
		)
	)
	(footprint "antmicro-footprints:L_1008_2520Metric"
		(layer "B.Cu")
		(at 83.876 86.45 180)
		(descr "Inductor SMD 1008 (2520 Metric)")
		(tags "inductor")
		(property "Reference" "L2"
			(at -3.2 0.8 0)
			(layer "B.SilkS")
			(effects
				(font
					(size 0.7 0.7)
					(thickness 0.15)
				)
				(justify left bottom mirror)
			)
		)
		(property "Value" "L_3u3_2.5A_1008"
			(at 0 -2.5 0)
			(layer "B.Fab")
			(effects
				(font
					(size 0.7 0.7)
					(thickness 0.15)
				)
				(justify left bottom mirror)
			)
		)
		(property "Datasheet" "https://product.tdk.com/system/files/dam/doc/product/inductor/inductor/smd/catalog/inductor_automotive_power_tfm252012alma_en.pdf"
			(at 0 0 180)
			(layer "F.Fab")
			(hide yes)
			(effects
				(font
					(size 1.27 1.27)
					(thickness 0.15)
				)
			)
		)
		(property "Description" "3.3 µH Shielded Thin Film Inductor 2 A 140mOhm Max 1008 (2520 Metric)"
			(at 0 0 180)
			(layer "F.Fab")
			(hide yes)
			(effects
				(font
					(size 1.27 1.27)
					(thickness 0.15)
				)
			)
		)
		(property "MPN" "TFM252012ALMA3R3MTAA"
			(at 0 0 180)
			(unlocked yes)
			(layer "B.Fab")
			(hide yes)
			(effects
				(font
					(size 1 1)
					(thickness 0.15)
				)
				(justify mirror)
			)
		)
		(property "ISat" "2.1 A"
			(at 0 0 180)
			(unlocked yes)
			(layer "B.Fab")
			(hide yes)
			(effects
				(font
					(size 1 1)
					(thickness 0.15)
				)
				(justify mirror)
			)
		)
		(property "IMax" "2.5 A"
			(at 0 0 180)
			(unlocked yes)
			(layer "B.Fab")
			(hide yes)
			(effects
				(font
					(size 1 1)
					(thickness 0.15)
				)
				(justify mirror)
			)
		)
		(property "Manufacturer" "TDK"
			(at 0 0 180)
			(unlocked yes)
			(layer "B.Fab")
			(hide yes)
			(effects
				(font
					(size 1 1)
					(thickness 0.15)
				)
				(justify mirror)
			)
		)
		(property "Val" "3u3/2.5A"
			(at 0 0 180)
			(unlocked yes)
			(layer "B.Fab")
			(hide yes)
			(effects
				(font
					(size 1 1)
					(thickness 0.15)
				)
				(justify mirror)
			)
		)
		(property "Size" "2.5x2.0"
			(at 0 0 180)
			(unlocked yes)
			(layer "B.Fab")
			(hide yes)
			(effects
				(font
					(size 1 1)
					(thickness 0.15)
				)
				(justify mirror)
			)
		)
		(property "Author" "Antmicro"
			(at 0 0 180)
			(unlocked yes)
			(layer "B.Fab")
			(hide yes)
			(effects
				(font
					(size 1 1)
					(thickness 0.15)
				)
				(justify mirror)
			)
		)
		(property "License" "Apache-2.0"
			(at 0 0 180)
			(unlocked yes)
			(layer "B.Fab")
			(hide yes)
			(effects
				(font
					(size 1 1)
					(thickness 0.15)
				)
				(justify mirror)
			)
		)
		(sheetname "/DC-DC Converters/")
		(sheetfile "dc-dc_converters.kicad_sch")
		(attr smd)
		(fp_line
			(start 0.261 1.111)
			(end -0.264 1.111)
			(stroke
				(width 0.15)
				(type solid)
			)
			(layer "B.SilkS")
		)
		(fp_line
			(start 0.261 -1.11)
			(end -0.264 -1.11)
			(stroke
				(width 0.15)
				(type solid)
			)
			(layer "B.SilkS")
		)
		(fp_rect
			(start -1.95 1.25)
			(end 1.95 -1.25)
			(stroke
				(width 0.05)
				(type solid)
			)
			(fill no)
			(layer "B.CrtYd")
		)
		(fp_line
			(start 1.249 0.999)
			(end -1.05 0.999)
			(stroke
				(width 0.15)
				(type solid)
			)
			(layer "B.Fab")
		)
		(fp_line
			(start 1.249 -0.997)
			(end 1.249 0.999)
			(stroke
				(width 0.15)
				(type solid)
			)
			(layer "B.Fab")
		)
		(fp_line
			(start -1.05 0.999)
			(end -1.25 0.8)
			(stroke
				(width 0.15)
				(type solid)
			)
			(layer "B.Fab")
		)
		(fp_line
			(start -1.25 0.8)
			(end -1.25 -0.997)
			(stroke
				(width 0.15)
				(type solid)
			)
			(layer "B.Fab")
		)
		(fp_line
			(start -1.25 -0.997)
			(end 1.249 -0.997)
			(stroke
				(width 0.15)
				(type solid)
			)
			(layer "B.Fab")
		)
		(pad "1" smd roundrect
			(at -1.075 0 180)
			(size 1.25 2.2)
			(layers "B.Cu" "B.Mask" "B.Paste")
			(roundrect_rratio 0.1)
			(net 21 "Net-(U3-SW)")
			(pintype "passive")
		)
		(pad "2" smd roundrect
			(at 1.075 0 180)
			(size 1.25 2.2)
			(layers "B.Cu" "B.Mask" "B.Paste")
			(roundrect_rratio 0.1)
			(net 25 "+5V")
			(pintype "passive")
		)
	)
	(footprint "antmicro-footprints:C_0603_1608Metric"
		(layer "B.Cu")
		(at 83.9 82.8 -90)
		(descr "Capacitor SMD 0603")
		(tags "capacitor 0603")
		(property "Reference" "C22"
			(at -6.473 0.207 90)
			(layer "B.SilkS")
			(effects
				(font
					(size 0.7 0.7)
					(thickness 0.15)
				)
				(justify left bottom mirror)
			)
		)
		(property "Value" "C_10u_25V_0603"
			(at -1.42757 -1.770288 90)
			(layer "B.Fab")
			(effects
				(font
					(size 0.7 0.7)
					(thickness 0.15)
				)
				(justify left bottom mirror)
			)
		)
		(property "Datasheet" "https://product.tdk.com/en/search/capacitor/ceramic/mlcc/info?part_no=C1608X5R1E106M080AC"
			(at 0 0 270)
			(layer "F.Fab")
			(hide yes)
			(effects
				(font
					(size 1.27 1.27)
					(thickness 0.15)
				)
			)
		)
		(property "Description" "SMD Multilayer Ceramic Capacitor, 10 µF, 25 V, 0603 [1608 Metric], ± 20%, X5R, C"
			(at 0 0 270)
			(layer "F.Fab")
			(hide yes)
			(effects
				(font
					(size 1.27 1.27)
					(thickness 0.15)
				)
			)
		)
		(property "MPN" "C1608X5R1E106M080AC"
			(at 0 0 270)
			(unlocked yes)
			(layer "B.Fab")
			(hide yes)
			(effects
				(font
					(size 1 1)
					(thickness 0.15)
				)
				(justify mirror)
			)
		)
		(property "Manufacturer" "TDK"
			(at 0 0 270)
			(unlocked yes)
			(layer "B.Fab")
			(hide yes)
			(effects
				(font
					(size 1 1)
					(thickness 0.15)
				)
				(justify mirror)
			)
		)
		(property "License" "Apache-2.0"
			(at 0 0 270)
			(unlocked yes)
			(layer "B.Fab")
			(hide yes)
			(effects
				(font
					(size 1 1)
					(thickness 0.15)
				)
				(justify mirror)
			)
		)
		(property "Author" "Antmicro"
			(at 0 0 270)
			(unlocked yes)
			(layer "B.Fab")
			(hide yes)
			(effects
				(font
					(size 1 1)
					(thickness 0.15)
				)
				(justify mirror)
			)
		)
		(property "Val" "10u"
			(at 0 0 270)
			(unlocked yes)
			(layer "B.Fab")
			(hide yes)
			(effects
				(font
					(size 1 1)
					(thickness 0.15)
				)
				(justify mirror)
			)
		)
		(property "Voltage" "25V"
			(at 0 0 270)
			(unlocked yes)
			(layer "B.Fab")
			(hide yes)
			(effects
				(font
					(size 1 1)
					(thickness 0.15)
				)
				(justify mirror)
			)
		)
		(property "Dielectric" ""
			(at 0 0 270)
			(unlocked yes)
			(layer "B.Fab")
			(hide yes)
			(effects
				(font
					(size 1 1)
					(thickness 0.15)
				)
				(justify mirror)
			)
		)
		(sheetname "/DC-DC Converters/")
		(sheetfile "dc-dc_converters.kicad_sch")
		(attr smd)
		(fp_line
			(start 0.15 0.4)
			(end -0.15 0.4)
			(stroke
				(width 0.15)
				(type solid)
			)
			(layer "B.SilkS")
		)
		(fp_line
			(start 0.15 -0.4)
			(end -0.15 -0.4)
			(stroke
				(width 0.15)
				(type solid)
			)
			(layer "B.SilkS")
		)
		(fp_rect
			(start -1.25 0.65)
			(end 1.25 -0.65)
			(stroke
				(width 0.05)
				(type solid)
			)
			(fill no)
			(layer "B.CrtYd")
		)
		(fp_rect
			(start -0.8 0.4)
			(end 0.8 -0.4)
			(stroke
				(width 0.15)
				(type solid)
			)
			(fill no)
			(layer "B.Fab")
		)
		(pad "1" smd roundrect
			(at -0.7 0 270)
			(size 0.8 1)
			(layers "B.Cu" "B.Mask" "B.Paste")
			(roundrect_rratio 0.2)
			(net 2 "GND")
			(pintype "passive")
		)
		(pad "2" smd roundrect
			(at 0.7 0 270)
			(size 0.8 1)
			(layers "B.Cu" "B.Mask" "B.Paste")
			(roundrect_rratio 0.2)
			(net 5 "+12V")
			(pintype "passive")
		)
	)
	(footprint "antmicro-footprints:C_0805_2012Metric"
		(layer "B.Cu")
		(at 90.75 93.05 -90)
		(descr "Capacitor SMD 0805")
		(tags "capacitor SMD 0805")
		(property "Reference" "C29"
			(at -18.3 6.674 180)
			(layer "B.SilkS")
			(effects
				(font
					(size 0.7 0.7)
					(thickness 0.15)
				)
				(justify left bottom mirror)
			)
		)
		(property "Value" "C_22u_25V_0805"
			(at -2.055717 -1.963152 90)
			(layer "B.Fab")
			(effects
				(font
					(size 0.7 0.7)
					(thickness 0.15)
				)
				(justify left bottom mirror)
			)
		)
		(property "Datasheet" "https://product.samsungsem.com/mlcc/CL21A226MAYNNN.do"
			(at 0 0 270)
			(layer "F.Fab")
			(hide yes)
			(effects
				(font
					(size 1.27 1.27)
					(thickness 0.15)
				)
			)
		)
		(property "Description" "SMT Multilayer Ceramic Capacitor, 22uF, +/-20%, 25V, X5R, 0805 [2012 Metric]"
			(at 0 0 270)
			(layer "F.Fab")
			(hide yes)
			(effects
				(font
					(size 1.27 1.27)
					(thickness 0.15)
				)
			)
		)
		(property "MPN" "CL21A226MAYNNNE"
			(at 0 0 270)
			(unlocked yes)
			(layer "B.Fab")
			(hide yes)
			(effects
				(font
					(size 1 1)
					(thickness 0.15)
				)
				(justify mirror)
			)
		)
		(property "Manufacturer" "Samsung Electro-Mechanics"
			(at 0 0 270)
			(unlocked yes)
			(layer "B.Fab")
			(hide yes)
			(effects
				(font
					(size 1 1)
					(thickness 0.15)
				)
				(justify mirror)
			)
		)
		(property "License" "Apache-2.0"
			(at 0 0 270)
			(unlocked yes)
			(layer "B.Fab")
			(hide yes)
			(effects
				(font
					(size 1 1)
					(thickness 0.15)
				)
				(justify mirror)
			)
		)
		(property "Author" "Antmicro"
			(at 0 0 270)
			(unlocked yes)
			(layer "B.Fab")
			(hide yes)
			(effects
				(font
					(size 1 1)
					(thickness 0.15)
				)
				(justify mirror)
			)
		)
		(property "Val" "22u"
			(at 0 0 270)
			(unlocked yes)
			(layer "B.Fab")
			(hide yes)
			(effects
				(font
					(size 1 1)
					(thickness 0.15)
				)
				(justify mirror)
			)
		)
		(property "Voltage" "25V"
			(at 0 0 270)
			(unlocked yes)
			(layer "B.Fab")
			(hide yes)
			(effects
				(font
					(size 1 1)
					(thickness 0.15)
				)
				(justify mirror)
			)
		)
		(property "Dielectric" "X5R"
			(at 0 0 270)
			(unlocked yes)
			(layer "B.Fab")
			(hide yes)
			(effects
				(font
					(size 1 1)
					(thickness 0.15)
				)
				(justify mirror)
			)
		)
		(property "Public" "False"
			(at 0 0 270)
			(unlocked yes)
			(layer "B.Fab")
			(hide yes)
			(effects
				(font
					(size 1 1)
					(thickness 0.15)
				)
				(justify mirror)
			)
		)
		(sheetname "/DC-DC Converters/")
		(sheetfile "dc-dc_converters.kicad_sch")
		(attr smd)
		(fp_line
			(start 0.3 0.7)
			(end -0.3 0.7)
			(stroke
				(width 0.15)
				(type solid)
			)
			(layer "B.SilkS")
		)
		(fp_line
			(start 0.3 -0.7)
			(end -0.3 -0.7)
			(stroke
				(width 0.15)
				(type solid)
			)
			(layer "B.SilkS")
		)
		(fp_rect
			(start 1.95 0.9)
			(end -1.95 -0.9)
			(stroke
				(width 0.05)
				(type default)
			)
			(fill no)
			(layer "B.CrtYd")
		)
		(fp_rect
			(start -0.95 0.675)
			(end 0.95 -0.675)
			(stroke
				(width 0.15)
				(type solid)
			)
			(fill no)
			(layer "B.Fab")
		)
		(pad "1" smd roundrect
			(at -1.1 0 270)
			(size 1.2 1.3)
			(layers "B.Cu" "B.Mask" "B.Paste")
			(roundrect_rratio 0.25)
			(net 2 "GND")
			(pintype "passive")
		)
		(pad "2" smd roundrect
			(at 1.1 0 270)
			(size 1.2 1.3)
			(layers "B.Cu" "B.Mask" "B.Paste")
			(roundrect_rratio 0.25)
			(net 5 "+12V")
			(pintype "passive")
		)
	)
)
